(kicad_pcb
	(version 20240108)
	(generator "pcbnew")
	(generator_version "8.0")
	(general
		(thickness 1.6)
		(legacy_teardrops no)
	)
	(paper "A4")
	(title_block
		(title "Jetson Orin Baseboard OCuLink Expansion")
		(date "2025-03-18")
		(rev "1.1.0")
		(company "Antmicro Ltd")
		(comment 1 "www.antmicro.com")
		(comment 9 "footprints 62-62 of 119")
	)
	(layers
		(0 "F.Cu" signal)
		(1 "In1.Cu" signal)
		(2 "In2.Cu" signal)
		(31 "B.Cu" signal)
		(32 "B.Adhes" user "B.Adhesive")
		(33 "F.Adhes" user "F.Adhesive")
		(34 "B.Paste" user)
		(35 "F.Paste" user)
		(36 "B.SilkS" user "B.Silkscreen")
		(37 "F.SilkS" user "F.Silkscreen")
		(38 "B.Mask" user)
		(39 "F.Mask" user)
		(40 "Dwgs.User" user "User.Drawings")
		(41 "Cmts.User" user "User.Comments")
		(42 "Eco1.User" user "User.Eco1")
		(43 "Eco2.User" user "User.Eco2")
		(44 "Edge.Cuts" user)
		(45 "Margin" user)
		(46 "B.CrtYd" user "B.Courtyard")
		(47 "F.CrtYd" user "F.Courtyard")
		(48 "B.Fab" user)
		(49 "F.Fab" user)
	)
	(footprint "antmicro-footprints:antmicro-logo_scaled_15mm"
		(layer "B.Cu")
		(at 118.795 94.22 180)
		(property "Reference" "N2"
			(at 0.1 3 0)
			(layer "B.SilkS")
			(hide yes)
			(effects
				(font
					(size 0.7 0.7)
					(thickness 0.15)
				)
				(justify left bottom mirror)
			)
		)
		(property "Value" "antmicro_logo"
			(at 0 -3.1 0)
			(layer "B.Fab")
			(hide yes)
			(effects
				(font
					(size 0.7 0.7)
					(thickness 0.15)
				)
				(justify left bottom mirror)
			)
		)
		(property "Footprint" "antmicro-footprints:antmicro-logo_scaled_15mm"
			(at 0 0 0)
			(layer "B.Fab")
			(hide yes)
			(effects
				(font
					(size 1.27 1.27)
					(thickness 0.15)
				)
				(justify mirror)
			)
		)
		(property "Description" "Mechanical part"
			(at 0 0 0)
			(layer "B.Fab")
			(hide yes)
			(effects
				(font
					(size 1.27 1.27)
					(thickness 0.15)
				)
				(justify mirror)
			)
		)
		(property "MPN" ""
			(at 0 0 0)
			(unlocked yes)
			(layer "B.Fab")
			(hide yes)
			(effects
				(font
					(size 1 1)
					(thickness 0.15)
				)
				(justify mirror)
			)
		)
		(property "Manufacturer" ""
			(at 0 0 0)
			(unlocked yes)
			(layer "B.Fab")
			(hide yes)
			(effects
				(font
					(size 1 1)
					(thickness 0.15)
				)
				(justify mirror)
			)
		)
		(property "Author" "Antmicro"
			(at 0 0 0)
			(unlocked yes)
			(layer "B.Fab")
			(hide yes)
			(effects
				(font
					(size 1 1)
					(thickness 0.15)
				)
				(justify mirror)
			)
		)
		(property "License" "Apache-2.0"
			(at 0 0 0)
			(unlocked yes)
			(layer "B.Fab")
			(hide yes)
			(effects
				(font
					(size 1 1)
					(thickness 0.15)
				)
				(justify mirror)
			)
		)
		(sheetname "Root")
		(sheetfile "jetson-orin-baseboard-oculink-expansion.kicad_sch")
		(attr exclude_from_pos_files exclude_from_bom allow_soldermask_bridges)
	)
)
